# BASEBOARD_FAB2 (Tioga Pass) — schematic netlist excerpt (pin names and nets, part order shuffled) for the footprints in the layout excerpt that follows; sources: Cadence DE-HDL packaged netlist, KiCad conversion of Wiwynn_Tioga_Pass_MB.brd

C30W5  SC22U16V5MX-4-GP  20%  pkg SMD-BCG5  page 253 : \1\ = P5V_STBY_USBC ; \2\ = GND
R3R1  RES  1.00K 1% CHIP  pkg 0402  page 92 : A = PD_GTL2104_DIR_1 ; B = GND
R6U13  RES  20.0 1% CHIP  pkg 0402  page 99 : A = SMB_DDR_GHJ_VPP_SCL_R ; B = SMB_DDR_GHJ_VPP_SCL

(kicad_pcb
	(version 20260206)
	(generator "pcbnew")
	(generator_version "10.0")
	(general
		(thickness 1.6)
		(legacy_teardrops no)
	)
	(paper "A4")
	(title_block
		(title "Wiwynn_Tioga_Pass_MB.brd")
		(comment 1 "Tioga Pass / footprints 3509-3512 of 4770")
	)
	(layers
		(0 "F.Cu" signal "TOP")
		(4 "In1.Cu" signal "L2GND")
		(6 "In2.Cu" signal "L3")
		(8 "In3.Cu" signal "L4GND")
		(10 "In4.Cu" signal "L5")
		(12 "In5.Cu" signal "L6GND")
		(14 "In6.Cu" signal "L7VCC")
		(16 "In7.Cu" signal "L8VCC")
		(18 "In8.Cu" signal "L9GND")
		(20 "In9.Cu" signal "L10")
		(22 "In10.Cu" signal "L11GND")
		(24 "In11.Cu" signal "L12")
		(26 "In12.Cu" signal "L13GND")
		(2 "B.Cu" signal "BOTTOM")
		(9 "F.Adhes" user "F.Adhesive")
		(11 "B.Adhes" user "B.Adhesive")
		(13 "F.Paste" user "Package Geometry/Pastemask Top")
		(15 "B.Paste" user "Package Geometry/Pastemask Bottom")
		(5 "F.SilkS" user "Ref Des/Silkscreen Top")
		(7 "B.SilkS" user "Ref Des/Silkscreen Bottom")
		(1 "F.Mask" user "Board Geometry/Soldermask Top")
		(3 "B.Mask" user "Board Geometry/Soldermask Bottom")
		(17 "Dwgs.User" user "User.Drawings")
		(19 "Cmts.User" user "User.Comments")
		(21 "Eco1.User" user "User.Eco1")
		(23 "Eco2.User" user "User.Eco2")
		(25 "Edge.Cuts" user "Board Geometry/Outline")
		(27 "Margin" user)
		(31 "F.CrtYd" user "Package Geometry/Place Bound Top")
		(29 "B.CrtYd" user "Package Geometry/Place Bound Bottom")
		(35 "F.Fab" user "Ref Des/Assembly Top")
		(33 "B.Fab" user "Ref Des/Assembly Bottom")
	)
	(footprint ""
		(layer "B.Cu")
		(at 372.676166 -61.098938 90)
		(property "Reference" "R3R1"
			(at 0 0 90)
			(layer "B.SilkS")
			(hide yes)
			(effects
				(font
					(size 1.27 1.27)
				)
				(justify mirror)
			)
		)
		(property "Value" ""
			(at 0 0 90)
			(layer "B.Fab")
			(effects
				(font
					(size 1.27 1.27)
				)
				(justify mirror)
			)
		)
		(duplicate_pad_numbers_are_jumpers no)
		(fp_poly
			(pts
				(xy 0.2794 -0.1016) (xy -0.2794 -0.1016) (xy -0.2794 0.9906) (xy 0.2794 0.9906)
			)
			(stroke
				(width 0)
				(type default)
			)
			(fill no)
			(layer "B.CrtYd")
		)
		(fp_line
			(start 0.2794 -0.1016)
			(end 0.2794 0.9906)
			(stroke
				(width 0.1)
				(type default)
			)
			(layer "B.Fab")
		)
		(fp_line
			(start -0.2794 -0.1016)
			(end 0.2794 -0.1016)
			(stroke
				(width 0.1)
				(type default)
			)
			(layer "B.Fab")
		)
		(fp_line
			(start 0.2794 0.9906)
			(end -0.2794 0.9906)
			(stroke
				(width 0.1)
				(type default)
			)
			(layer "B.Fab")
		)
		(fp_line
			(start -0.2794 0.9906)
			(end -0.2794 -0.1016)
			(stroke
				(width 0.1)
				(type default)
			)
			(layer "B.Fab")
		)
		(pad "1" smd rect
			(at 0 0 270)
			(size 0.508 0.508)
			(layers "B.Cu" "B.Mask" "B.Paste")
			(net "PD_GTL2104_DIR_1")
		)
		(pad "2" smd rect
			(at 0 0.889 270)
			(size 0.508 0.508)
			(layers "B.Cu" "B.Mask" "B.Paste")
			(net "GND")
		)
		(zone
			(layer "B.Cu")
			(hatch none 0.5)
			(connect_pads
				(clearance 0)
			)
			(min_thickness 0.25)
			(keepout
				(tracks allowed)
				(vias not_allowed)
				(pads allowed)
				(copperpour not_allowed)
				(footprints allowed)
			)
			(placement
				(enabled no)
				(sheetname "")
			)
			(fill
				(thermal_gap 0.5)
				(thermal_bridge_width 0.5)
				(island_removal_mode 0)
			)
			(polygon
				(pts
					(xy 372.930166 -61.352938) (xy 372.930166 -60.844938) (xy 373.311166 -60.844938) (xy 373.311166 -61.352938)
				)
			)
		)
		(zone
			(layer "B.Cu")
			(hatch none 0.5)
			(connect_pads
				(clearance 0)
			)
			(min_thickness 0.25)
			(keepout
				(tracks not_allowed)
				(vias allowed)
				(pads allowed)
				(copperpour not_allowed)
				(footprints allowed)
			)
			(placement
				(enabled no)
				(sheetname "")
			)
			(fill
				(thermal_gap 0.5)
				(thermal_bridge_width 0.5)
				(island_removal_mode 0)
			)
			(polygon
				(pts
					(xy 373.311166 -61.352938) (xy 373.311166 -60.844938) (xy 372.930166 -60.844938) (xy 372.930166 -61.352938)
				)
			)
		)
	)
	(footprint ""
		(layer "B.Cu")
		(at 166.68877 2.209546 90)
		(property "Reference" "R6U13"
			(at 0 0 90)
			(layer "B.SilkS")
			(hide yes)
			(effects
				(font
					(size 1.27 1.27)
				)
				(justify mirror)
			)
		)
		(property "Value" ""
			(at 0 0 90)
			(layer "B.Fab")
			(effects
				(font
					(size 1.27 1.27)
				)
				(justify mirror)
			)
		)
		(duplicate_pad_numbers_are_jumpers no)
		(fp_poly
			(pts
				(xy 0.2794 -0.1016) (xy -0.2794 -0.1016) (xy -0.2794 0.9906) (xy 0.2794 0.9906)
			)
			(stroke
				(width 0)
				(type default)
			)
			(fill no)
			(layer "B.CrtYd")
		)
		(fp_line
			(start 0.2794 -0.1016)
			(end 0.2794 0.9906)
			(stroke
				(width 0.1)
				(type default)
			)
			(layer "B.Fab")
		)
		(fp_line
			(start -0.2794 -0.1016)
			(end 0.2794 -0.1016)
			(stroke
				(width 0.1)
				(type default)
			)
			(layer "B.Fab")
		)
		(fp_line
			(start 0.2794 0.9906)
			(end -0.2794 0.9906)
			(stroke
				(width 0.1)
				(type default)
			)
			(layer "B.Fab")
		)
		(fp_line
			(start -0.2794 0.9906)
			(end -0.2794 -0.1016)
			(stroke
				(width 0.1)
				(type default)
			)
			(layer "B.Fab")
		)
		(pad "1" smd rect
			(at 0 0 270)
			(size 0.508 0.508)
			(layers "B.Cu" "B.Mask" "B.Paste")
			(net "SMB_DDR_GHJ_VPP_SCL_R")
		)
		(pad "2" smd rect
			(at 0 0.889 270)
			(size 0.508 0.508)
			(layers "B.Cu" "B.Mask" "B.Paste")
			(net "SMB_DDR_GHJ_VPP_SCL")
		)
		(zone
			(layer "B.Cu")
			(hatch none 0.5)
			(connect_pads
				(clearance 0)
			)
			(min_thickness 0.25)
			(keepout
				(tracks allowed)
				(vias not_allowed)
				(pads allowed)
				(copperpour not_allowed)
				(footprints allowed)
			)
			(placement
				(enabled no)
				(sheetname "")
			)
			(fill
				(thermal_gap 0.5)
				(thermal_bridge_width 0.5)
				(island_removal_mode 0)
			)
			(polygon
				(pts
					(xy 166.94277 1.955546) (xy 166.94277 2.463546) (xy 167.32377 2.463546) (xy 167.32377 1.955546)
				)
			)
		)
		(zone
			(layer "B.Cu")
			(hatch none 0.5)
			(connect_pads
				(clearance 0)
			)
			(min_thickness 0.25)
			(keepout
				(tracks not_allowed)
				(vias allowed)
				(pads allowed)
				(copperpour not_allowed)
				(footprints allowed)
			)
			(placement
				(enabled no)
				(sheetname "")
			)
			(fill
				(thermal_gap 0.5)
				(thermal_bridge_width 0.5)
				(island_removal_mode 0)
			)
			(polygon
				(pts
					(xy 167.32377 1.955546) (xy 167.32377 2.463546) (xy 166.94277 2.463546) (xy 166.94277 1.955546)
				)
			)
		)
	)
	(footprint ""
		(layer "B.Cu")
		(at 499.995698 -55.370222)
		(property "Reference" "C30W5"
			(at 0 0 0)
			(layer "B.SilkS")
			(hide yes)
			(effects
				(font
					(size 1.27 1.27)
				)
				(justify mirror)
			)
		)
		(property "Value" "*"
			(at 0.0762 -6.2357 0)
			(unlocked yes)
			(layer "B.Fab")
			(hide yes)
			(effects
				(font
					(size 1.27 1.016)
					(thickness 0.1524)
				)
				(justify mirror)
			)
		)
		(property "Device Type" "SC22U16V5MX-4-GP_SMD-BCG5-SC22A"
			(at 0.0762 -8.2677 0)
			(unlocked yes)
			(layer "B.Fab")
			(hide yes)
			(effects
				(font
					(size 1.27 1.016)
					(thickness 0.1524)
				)
				(justify mirror)
			)
		)
		(duplicate_pad_numbers_are_jumpers no)
		(fp_line
			(start -0.635 0)
			(end 0.635 0)
			(stroke
				(width 0.508)
				(type default)
			)
			(layer "B.SilkS")
		)
		(fp_rect
			(start 0.9652 1.778)
			(end -0.9652 -1.778)
			(stroke
				(width 0)
				(type default)
			)
			(fill no)
			(layer "B.CrtYd")
		)
		(fp_poly
			(pts
				(xy 0.9652 -1.778) (xy -0.9652 -1.778) (xy -0.9652 1.778) (xy 0.9652 1.778)
			)
			(stroke
				(width 0)
				(type default)
			)
			(fill no)
			(layer "B.Fab")
		)
		(pad "1" smd rect
			(at 0 -0.9652 180)
			(size 1.397 1.143)
			(layers "B.Cu" "B.Mask" "B.Paste")
			(net "P5V_STBY_USBC")
		)
		(pad "2" smd rect
			(at 0 0.9652 180)
			(size 1.397 1.143)
			(layers "B.Cu" "B.Mask" "B.Paste")
			(net "GND")
		)
	)
	(footprint ""
		(layer "B.Cu")
		(at 44.97578 -30.7975)
		(property "Reference" ""
			(at 0 0 0)
			(layer "B.SilkS")
			(hide yes)
			(effects
				(font
					(size 1.27 1.27)
				)
				(justify mirror)
			)
		)
		(property "Value" ""
			(at 0 0 0)
			(layer "B.Fab")
			(effects
				(font
					(size 1.27 1.27)
				)
				(justify mirror)
			)
		)
		(duplicate_pad_numbers_are_jumpers no)
		(fp_poly
			(pts
				(arc
					(start 2.032 0)
					(mid -2.032 0)
					(end 2.032 0)
				)
			)
			(stroke
				(width 0)
				(type default)
			)
			(fill no)
			(layer "B.CrtYd")
		)
		(pad "1" smd circle
			(at 0 0 180)
			(size 1.016 1.016)
			(layers "B.Cu" "B.Mask" "B.Paste")
			(net "Net_386")
		)
		(zone
			(layer "B.Cu")
			(hatch none 0.5)
			(connect_pads
				(clearance 0)
			)
			(min_thickness 0.25)
			(keepout
				(tracks not_allowed)
				(vias allowed)
				(pads allowed)
				(copperpour not_allowed)
				(footprints allowed)
			)
			(placement
				(enabled no)
				(sheetname "")
			)
			(fill
				(thermal_gap 0.5)
				(thermal_bridge_width 0.5)
				(island_removal_mode 0)
			)
			(polygon
				(pts
					(arc
						(start 46.49978 -30.7975)
						(mid 43.45178 -30.7975)
						(end 46.49978 -30.7975)
					)
				)
			)
		)
	)
)
